(kicad_pcb
	(version 20260206)
	(generator "pcbnew")
	(generator_version "10.0")
	(general
		(thickness 1.6)
		(legacy_teardrops no)
	)
	(paper "A4")
	(title_block
		(title "Bryce Canyon_IOM_M2_16342-2_OCP.brd")
		(comment 1 "Bryce Canyon / footprints 624-629 of 1146")
	)
	(layers
		(0 "F.Cu" signal "TOP")
		(4 "In1.Cu" signal "L2GND")
		(6 "In2.Cu" signal "L3")
		(8 "In3.Cu" signal "L4VCC")
		(10 "In4.Cu" signal "L5VCC")
		(12 "In5.Cu" signal "L6")
		(14 "In6.Cu" signal "L7GND")
		(2 "B.Cu" signal "BOTTOM")
		(9 "F.Adhes" user "F.Adhesive")
		(11 "B.Adhes" user "B.Adhesive")
		(13 "F.Paste" user "Package Geometry/Pastemask Top")
		(15 "B.Paste" user "Package Geometry/Pastemask Bottom")
		(5 "F.SilkS" user "Ref Des/Silkscreen Top")
		(7 "B.SilkS" user "Ref Des/Silkscreen Bottom")
		(1 "F.Mask" user "Board Geometry/Soldermask Top")
		(3 "B.Mask" user "Board Geometry/Soldermask Bottom")
		(17 "Dwgs.User" user "User.Drawings")
		(19 "Cmts.User" user "User.Comments")
		(21 "Eco1.User" user "User.Eco1")
		(23 "Eco2.User" user "User.Eco2")
		(25 "Edge.Cuts" user "Board Geometry/Outline")
		(27 "Margin" user)
		(31 "F.CrtYd" user "Package Geometry/Place Bound Top")
		(29 "B.CrtYd" user "Package Geometry/Place Bound Bottom")
		(35 "F.Fab" user "Ref Des/Assembly Top")
		(33 "B.Fab" user "Ref Des/Assembly Bottom")
	)
	(footprint ""
		(layer "F.Cu")
		(at 9.779 -13.081)
		(property "Reference" "R65"
			(at 0 0 0)
			(layer "F.SilkS")
			(hide yes)
			(effects
				(font
					(size 1.27 1.27)
				)
			)
		)
		(property "Value" "8K2R2J-3-GP"
			(at 0.064008 -3.993896 0)
			(unlocked yes)
			(layer "F.Fab")
			(hide yes)
			(effects
				(font
					(size 1.016 1.016)
					(thickness 0.1524)
				)
			)
		)
		(property "Device Type" "R402H16"
			(at 0.064008 -5.517896 0)
			(unlocked yes)
			(layer "F.Fab")
			(hide yes)
			(effects
				(font
					(size 1.016 1.016)
					(thickness 0.1524)
				)
			)
		)
		(duplicate_pad_numbers_are_jumpers no)
		(fp_line
			(start -0.508 -0.9398)
			(end -0.508 0.9398)
			(stroke
				(width 0.1524)
				(type default)
			)
			(layer "F.SilkS")
		)
		(fp_line
			(start 0.508 -0.9398)
			(end -0.508 -0.9398)
			(stroke
				(width 0.1524)
				(type default)
			)
			(layer "F.SilkS")
		)
		(fp_rect
			(start -0.508 0.9398)
			(end 0.508 -0.9398)
			(stroke
				(width 0)
				(type default)
			)
			(fill no)
			(layer "F.CrtYd")
		)
		(fp_rect
			(start -0.508 0.9398)
			(end 0.508 -0.9398)
			(stroke
				(width 0)
				(type default)
			)
			(fill no)
			(layer "F.Fab")
		)
		(pad "1" smd custom
			(at 0 -0.4445)
			(size 0.1397 0.1397)
			(layers "F.Cu" "F.Mask" "F.Paste")
			(net "P3V3_STBY")
			(options
				(clearance outline)
				(anchor circle)
			)
			(primitives
				(gr_poly
					(pts
						(arc
							(start -0.1778 -0.2794)
							(mid -0.249642 -0.249642)
							(end -0.2794 -0.1778)
						)
						(arc
							(start -0.2794 0.1778)
							(mid -0.249642 0.249642)
							(end -0.1778 0.2794)
						)
						(arc
							(start 0.1778 0.2794)
							(mid 0.249642 0.249642)
							(end 0.2794 0.1778)
						)
						(arc
							(start 0.2794 -0.1778)
							(mid 0.249642 -0.249642)
							(end 0.1778 -0.2794)
						)
					)
					(width 0)
					(fill yes)
				)
			)
		)
		(pad "2" smd custom
			(at 0 0.4445)
			(size 0.1397 0.1397)
			(layers "F.Cu" "F.Mask" "F.Paste")
			(net "SYS_RST_BTN_IN_N")
			(options
				(clearance outline)
				(anchor circle)
			)
			(primitives
				(gr_poly
					(pts
						(arc
							(start -0.1778 -0.2794)
							(mid -0.249642 -0.249642)
							(end -0.2794 -0.1778)
						)
						(arc
							(start -0.2794 0.1778)
							(mid -0.249642 0.249642)
							(end -0.1778 0.2794)
						)
						(arc
							(start 0.1778 0.2794)
							(mid 0.249642 0.249642)
							(end 0.2794 0.1778)
						)
						(arc
							(start 0.2794 -0.1778)
							(mid 0.249642 -0.249642)
							(end 0.1778 -0.2794)
						)
					)
					(width 0)
					(fill yes)
				)
			)
		)
	)
	(footprint ""
		(layer "F.Cu")
		(at 40.6654 -158.0642)
		(property "Reference" "TP189"
			(at 0 0 0)
			(layer "F.SilkS")
			(hide yes)
			(effects
				(font
					(size 1.27 1.27)
				)
			)
		)
		(property "Value" "TPAD28-2-GP"
			(at -0.0127 -1.6637 0)
			(unlocked yes)
			(layer "F.Fab")
			(hide yes)
			(effects
				(font
					(size 1.016 1.016)
					(thickness 0.1524)
				)
			)
		)
		(property "Device Type" "TPAD28"
			(at -0.0127 -3.1877 0)
			(unlocked yes)
			(layer "F.Fab")
			(hide yes)
			(effects
				(font
					(size 1.016 1.016)
					(thickness 0.1524)
				)
			)
		)
		(duplicate_pad_numbers_are_jumpers no)
		(fp_poly
			(pts
				(arc
					(start 0.3556 0)
					(mid -0.3556 0)
					(end 0.3556 0)
				)
			)
			(stroke
				(width 0)
				(type default)
			)
			(fill no)
			(layer "F.CrtYd")
		)
		(fp_poly
			(pts
				(arc
					(start 0.6096 0)
					(mid -0.6096 0)
					(end 0.6096 0)
				)
			)
			(stroke
				(width 0)
				(type default)
			)
			(fill no)
			(layer "F.Fab")
		)
		(pad "1" smd circle
			(at 0 0)
			(size 0.7112 0.7112)
			(layers "F.Cu" "F.Mask" "F.Paste")
			(net "TP_BMC_GPIOL3")
		)
	)
	(footprint ""
		(layer "F.Cu")
		(at 88.773 -130.0226 -90)
		(property "Reference" "R421"
			(at 0 0 270)
			(layer "F.SilkS")
			(hide yes)
			(effects
				(font
					(size 1.27 1.27)
				)
			)
		)
		(property "Value" "10KR2F-2-GP"
			(at 0.064008 -3.993896 270)
			(unlocked yes)
			(layer "F.Fab")
			(hide yes)
			(effects
				(font
					(size 1.016 1.016)
					(thickness 0.1524)
				)
			)
		)
		(property "Device Type" "R402H16"
			(at 0.064008 -5.517896 270)
			(unlocked yes)
			(layer "F.Fab")
			(hide yes)
			(effects
				(font
					(size 1.016 1.016)
					(thickness 0.1524)
				)
			)
		)
		(duplicate_pad_numbers_are_jumpers no)
		(fp_line
			(start -0.508 -0.9398)
			(end -0.508 0.9398)
			(stroke
				(width 0.1524)
				(type default)
			)
			(layer "F.SilkS")
		)
		(fp_line
			(start 0.508 -0.9398)
			(end -0.508 -0.9398)
			(stroke
				(width 0.1524)
				(type default)
			)
			(layer "F.SilkS")
		)
		(fp_rect
			(start -0.508 0.9398)
			(end 0.508 -0.9398)
			(stroke
				(width 0)
				(type default)
			)
			(fill no)
			(layer "F.CrtYd")
		)
		(fp_rect
			(start -0.508 0.9398)
			(end 0.508 -0.9398)
			(stroke
				(width 0)
				(type default)
			)
			(fill no)
			(layer "F.Fab")
		)
		(pad "1" smd custom
			(at 0 -0.4445 270)
			(size 0.1397 0.1397)
			(layers "F.Cu" "F.Mask" "F.Paste")
			(net "UART_SEL_MUX")
			(options
				(clearance outline)
				(anchor circle)
			)
			(primitives
				(gr_poly
					(pts
						(arc
							(start -0.1778 -0.2794)
							(mid -0.249642 -0.249642)
							(end -0.2794 -0.1778)
						)
						(arc
							(start -0.2794 0.1778)
							(mid -0.249642 0.249642)
							(end -0.1778 0.2794)
						)
						(arc
							(start 0.1778 0.2794)
							(mid 0.249642 0.249642)
							(end 0.2794 0.1778)
						)
						(arc
							(start 0.2794 -0.1778)
							(mid 0.249642 -0.249642)
							(end 0.1778 -0.2794)
						)
					)
					(width 0)
					(fill yes)
				)
			)
		)
		(pad "2" smd custom
			(at 0 0.4445 270)
			(size 0.1397 0.1397)
			(layers "F.Cu" "F.Mask" "F.Paste")
			(net "GND")
			(options
				(clearance outline)
				(anchor circle)
			)
			(primitives
				(gr_poly
					(pts
						(arc
							(start -0.1778 -0.2794)
							(mid -0.249642 -0.249642)
							(end -0.2794 -0.1778)
						)
						(arc
							(start -0.2794 0.1778)
							(mid -0.249642 0.249642)
							(end -0.1778 0.2794)
						)
						(arc
							(start 0.1778 0.2794)
							(mid 0.249642 0.249642)
							(end 0.2794 0.1778)
						)
						(arc
							(start 0.2794 -0.1778)
							(mid 0.249642 -0.249642)
							(end 0.1778 -0.2794)
						)
					)
					(width 0)
					(fill yes)
				)
			)
		)
	)
	(footprint ""
		(layer "F.Cu")
		(at 216.069672 -51.781456 -90)
		(property "Reference" "R477"
			(at 0 0 270)
			(layer "F.SilkS")
			(hide yes)
			(effects
				(font
					(size 1.27 1.27)
				)
			)
		)
		(property "Value" "619KR2F-GP"
			(at 0.064008 -3.993896 270)
			(unlocked yes)
			(layer "F.Fab")
			(hide yes)
			(effects
				(font
					(size 1.016 1.016)
					(thickness 0.1524)
				)
			)
		)
		(property "Device Type" "R402H16"
			(at 0.064008 -5.517896 270)
			(unlocked yes)
			(layer "F.Fab")
			(hide yes)
			(effects
				(font
					(size 1.016 1.016)
					(thickness 0.1524)
				)
			)
		)
		(duplicate_pad_numbers_are_jumpers no)
		(fp_line
			(start -0.508 -0.9398)
			(end -0.508 0.9398)
			(stroke
				(width 0.1524)
				(type default)
			)
			(layer "F.SilkS")
		)
		(fp_line
			(start 0.508 -0.9398)
			(end -0.508 -0.9398)
			(stroke
				(width 0.1524)
				(type default)
			)
			(layer "F.SilkS")
		)
		(fp_rect
			(start -0.508 0.9398)
			(end 0.508 -0.9398)
			(stroke
				(width 0)
				(type default)
			)
			(fill no)
			(layer "F.CrtYd")
		)
		(fp_rect
			(start -0.508 0.9398)
			(end 0.508 -0.9398)
			(stroke
				(width 0)
				(type default)
			)
			(fill no)
			(layer "F.Fab")
		)
		(pad "1" smd custom
			(at 0 -0.4445 270)
			(size 0.1397 0.1397)
			(layers "F.Cu" "F.Mask" "F.Paste")
			(net "P5V_RF")
			(options
				(clearance outline)
				(anchor circle)
			)
			(primitives
				(gr_poly
					(pts
						(arc
							(start -0.1778 -0.2794)
							(mid -0.249642 -0.249642)
							(end -0.2794 -0.1778)
						)
						(arc
							(start -0.2794 0.1778)
							(mid -0.249642 0.249642)
							(end -0.1778 0.2794)
						)
						(arc
							(start 0.1778 0.2794)
							(mid 0.249642 0.249642)
							(end 0.2794 0.1778)
						)
						(arc
							(start 0.2794 -0.1778)
							(mid 0.249642 -0.249642)
							(end 0.1778 -0.2794)
						)
					)
					(width 0)
					(fill yes)
				)
			)
		)
		(pad "2" smd custom
			(at 0 0.4445 270)
			(size 0.1397 0.1397)
			(layers "F.Cu" "F.Mask" "F.Paste")
			(net "AGND_P5V")
			(options
				(clearance outline)
				(anchor circle)
			)
			(primitives
				(gr_poly
					(pts
						(arc
							(start -0.1778 -0.2794)
							(mid -0.249642 -0.249642)
							(end -0.2794 -0.1778)
						)
						(arc
							(start -0.2794 0.1778)
							(mid -0.249642 0.249642)
							(end -0.1778 0.2794)
						)
						(arc
							(start 0.1778 0.2794)
							(mid 0.249642 0.249642)
							(end 0.2794 0.1778)
						)
						(arc
							(start 0.2794 -0.1778)
							(mid 0.249642 -0.249642)
							(end 0.1778 -0.2794)
						)
					)
					(width 0)
					(fill yes)
				)
			)
		)
	)
	(footprint ""
		(layer "F.Cu")
		(at 28.790646 -176.618138 180)
		(property "Reference" "R493"
			(at 0 0 180)
			(layer "F.SilkS")
			(hide yes)
			(effects
				(font
					(size 1.27 1.27)
				)
			)
		)
		(property "Value" "100KR2F-L1-GP"
			(at 0.064008 -3.993896 180)
			(unlocked yes)
			(layer "F.Fab")
			(hide yes)
			(effects
				(font
					(size 1.016 1.016)
					(thickness 0.1524)
				)
			)
		)
		(property "Device Type" "R402H16"
			(at 0.064008 -5.517896 180)
			(unlocked yes)
			(layer "F.Fab")
			(hide yes)
			(effects
				(font
					(size 1.016 1.016)
					(thickness 0.1524)
				)
			)
		)
		(duplicate_pad_numbers_are_jumpers no)
		(fp_line
			(start 0.508 -0.9398)
			(end -0.508 -0.9398)
			(stroke
				(width 0.1524)
				(type default)
			)
			(layer "F.SilkS")
		)
		(fp_line
			(start -0.508 -0.9398)
			(end -0.508 0.9398)
			(stroke
				(width 0.1524)
				(type default)
			)
			(layer "F.SilkS")
		)
		(fp_rect
			(start -0.508 0.9398)
			(end 0.508 -0.9398)
			(stroke
				(width 0)
				(type default)
			)
			(fill no)
			(layer "F.CrtYd")
		)
		(fp_rect
			(start -0.508 0.9398)
			(end 0.508 -0.9398)
			(stroke
				(width 0)
				(type default)
			)
			(fill no)
			(layer "F.Fab")
		)
		(pad "1" smd custom
			(at 0 -0.4445 180)
			(size 0.1397 0.1397)
			(layers "F.Cu" "F.Mask" "F.Paste")
			(net "AGND_P3V3_STBY")
			(options
				(clearance outline)
				(anchor circle)
			)
			(primitives
				(gr_poly
					(pts
						(arc
							(start -0.1778 -0.2794)
							(mid -0.249642 -0.249642)
							(end -0.2794 -0.1778)
						)
						(arc
							(start -0.2794 0.1778)
							(mid -0.249642 0.249642)
							(end -0.1778 0.2794)
						)
						(arc
							(start 0.1778 0.2794)
							(mid 0.249642 0.249642)
							(end 0.2794 0.1778)
						)
						(arc
							(start 0.2794 -0.1778)
							(mid 0.249642 -0.249642)
							(end 0.1778 -0.2794)
						)
					)
					(width 0)
					(fill yes)
				)
			)
		)
		(pad "2" smd custom
			(at 0 0.4445 180)
			(size 0.1397 0.1397)
			(layers "F.Cu" "F.Mask" "F.Paste")
			(net "P3V3_STBY_MODE")
			(options
				(clearance outline)
				(anchor circle)
			)
			(primitives
				(gr_poly
					(pts
						(arc
							(start -0.1778 -0.2794)
							(mid -0.249642 -0.249642)
							(end -0.2794 -0.1778)
						)
						(arc
							(start -0.2794 0.1778)
							(mid -0.249642 0.249642)
							(end -0.1778 0.2794)
						)
						(arc
							(start 0.1778 0.2794)
							(mid 0.249642 0.249642)
							(end 0.2794 0.1778)
						)
						(arc
							(start 0.2794 -0.1778)
							(mid 0.249642 -0.249642)
							(end 0.1778 -0.2794)
						)
					)
					(width 0)
					(fill yes)
				)
			)
		)
	)
	(footprint ""
		(layer "F.Cu")
		(at 220.883988 -48.58131 180)
		(property "Reference" "PU1"
			(at 0 0 180)
			(layer "F.SilkS")
			(hide yes)
			(effects
				(font
					(size 1.27 1.27)
				)
			)
		)
		(property "Value" "TPS53318DQPR-GP"
			(at -5.022088 -6.851904 180)
			(unlocked yes)
			(layer "F.Fab")
			(hide yes)
			(effects
				(font
					(size 1.016 1.016)
					(thickness 0.1524)
				)
			)
		)
		(property "Device Type" "DFN22G6050-G6133H60"
			(at -5.022088 -8.375904 180)
			(unlocked yes)
			(layer "F.Fab")
			(hide yes)
			(effects
				(font
					(size 1.016 1.016)
					(thickness 0.1524)
				)
			)
		)
		(duplicate_pad_numbers_are_jumpers no)
		(fp_line
			(start 3.5052 3.5179)
			(end 3.5052 2.2479)
			(stroke
				(width 0.1524)
				(type default)
			)
			(layer "F.SilkS")
		)
		(fp_line
			(start 2.2352 3.5179)
			(end 3.5052 3.5179)
			(stroke
				(width 0.1524)
				(type default)
			)
			(layer "F.SilkS")
		)
		(fp_line
			(start 1.500124 3.262122)
			(end 1.500124 4.024122)
			(stroke
				(width 0.1524)
				(type default)
			)
			(layer "F.SilkS")
		)
		(fp_line
			(start 0.500126 -3.262122)
			(end 0.500126 -3.770122)
			(stroke
				(width 0.1524)
				(type default)
			)
			(layer "F.SilkS")
		)
		(fp_line
			(start -0.999998 3.262122)
			(end -0.999998 3.770122)
			(stroke
				(width 0.1524)
				(type default)
			)
			(layer "F.SilkS")
		)
		(fp_line
			(start -1.999996 -3.262122)
			(end -1.999996 -4.024122)
			(stroke
				(width 0.1524)
				(type default)
			)
			(layer "F.SilkS")
		)
		(fp_line
			(start -2.2352 -3.5179)
			(end -3.5052 -3.5179)
			(stroke
				(width 0.1524)
				(type default)
			)
			(layer "F.SilkS")
		)
		(fp_line
			(start -3.5052 3.5179)
			(end -2.2352 3.5179)
			(stroke
				(width 0.1524)
				(type default)
			)
			(layer "F.SilkS")
		)
		(fp_line
			(start -3.5052 2.2479)
			(end -3.5052 3.5179)
			(stroke
				(width 0.1524)
				(type default)
			)
			(layer "F.SilkS")
		)
		(fp_line
			(start -3.5052 -3.5179)
			(end -3.5052 -2.2479)
			(stroke
				(width 0.1524)
				(type default)
			)
			(layer "F.SilkS")
		)
		(fp_poly
			(pts
				(xy 3.5052 -3.5179) (xy 2.4765 -3.5179) (xy 3.5052 -2.4892)
			)
			(stroke
				(width 0)
				(type default)
			)
			(fill yes)
			(layer "F.SilkS")
		)
		(fp_rect
			(start -2.9972 2.5019)
			(end 2.9972 -2.5019)
			(stroke
				(width 0)
				(type default)
			)
			(fill no)
			(layer "F.CrtYd")
		)
		(fp_poly
			(pts
				(xy 3.556 -2.5019) (xy -2.9972 -2.5019) (xy -2.9972 2.5019) (xy 2.9972 2.5019) (xy 2.9972 -2.4892)
				(xy 3.556 -2.4892) (xy 3.556 3.5179) (xy -3.556 3.5179) (xy -3.556 -3.5179) (xy 3.556 -3.5179)
			)
			(stroke
				(width 0)
				(type default)
			)
			(fill no)
			(layer "F.CrtYd")
		)
		(fp_rect
			(start -3.556 3.5179)
			(end 3.556 -3.5179)
			(stroke
				(width 0)
				(type default)
			)
			(fill no)
			(layer "F.Fab")
		)
		(pad "1" smd rect
			(at 2.500122 -2.449322 180)
			(size 0.3048 1.1176)
			(layers "F.Cu" "F.Mask" "F.Paste")
			(net "P5V_VFB")
		)
		(pad "2" smd rect
			(at 1.999996 -2.449322 180)
			(size 0.3048 1.1176)
			(layers "F.Cu" "F.Mask" "F.Paste")
			(net "P5V_EN_R")
		)
		(pad "3" smd rect
			(at 1.500124 -2.449322 180)
			(size 0.3048 1.1176)
			(layers "F.Cu" "F.Mask" "F.Paste")
			(net "PWRGD_P5V_STBY")
		)
		(pad "4" smd rect
			(at 0.999998 -2.449322 180)
			(size 0.3048 1.1176)
			(layers "F.Cu" "F.Mask" "F.Paste")
			(net "P5V_VBST")
		)
		(pad "5" smd rect
			(at 0.500126 -2.449322 180)
			(size 0.3048 1.1176)
			(layers "F.Cu" "F.Mask" "F.Paste")
			(net "AGND_P5V")
		)
		(pad "6" smd rect
			(at 0 -2.449322 180)
			(size 0.3048 1.1176)
			(layers "F.Cu" "F.Mask" "F.Paste")
			(net "P5V_LL")
		)
		(pad "7" smd rect
			(at -0.500126 -2.449322 180)
			(size 0.3048 1.1176)
			(layers "F.Cu" "F.Mask" "F.Paste")
			(net "P5V_LL")
		)
		(pad "8" smd rect
			(at -0.999998 -2.449322 180)
			(size 0.3048 1.1176)
			(layers "F.Cu" "F.Mask" "F.Paste")
			(net "P5V_LL")
		)
		(pad "9" smd rect
			(at -1.500124 -2.449322 180)
			(size 0.3048 1.1176)
			(layers "F.Cu" "F.Mask" "F.Paste")
			(net "P5V_LL")
		)
		(pad "10" smd rect
			(at -1.999996 -2.449322 180)
			(size 0.3048 1.1176)
			(layers "F.Cu" "F.Mask" "F.Paste")
			(net "P5V_LL")
		)
		(pad "11" smd rect
			(at -2.500122 -2.449322 180)
			(size 0.3048 1.1176)
			(layers "F.Cu" "F.Mask" "F.Paste")
			(net "P5V_LL")
		)
		(pad "12" smd rect
			(at -2.500122 2.449322 180)
			(size 0.3048 1.1176)
			(layers "F.Cu" "F.Mask" "F.Paste")
			(net "P12V_STBY_VIN_PU1")
		)
		(pad "13" smd rect
			(at -1.999996 2.449322 180)
			(size 0.3048 1.1176)
			(layers "F.Cu" "F.Mask" "F.Paste")
			(net "P12V_STBY_VIN_PU1")
		)
		(pad "14" smd rect
			(at -1.500124 2.449322 180)
			(size 0.3048 1.1176)
			(layers "F.Cu" "F.Mask" "F.Paste")
			(net "P12V_STBY_VIN_PU1")
		)
		(pad "15" smd rect
			(at -0.999998 2.449322 180)
			(size 0.3048 1.1176)
			(layers "F.Cu" "F.Mask" "F.Paste")
			(net "P12V_STBY_VIN_PU1")
		)
		(pad "16" smd rect
			(at -0.500126 2.449322 180)
			(size 0.3048 1.1176)
			(layers "F.Cu" "F.Mask" "F.Paste")
			(net "P12V_STBY_VIN_PU1")
		)
		(pad "17" smd rect
			(at 0 2.449322 180)
			(size 0.3048 1.1176)
			(layers "F.Cu" "F.Mask" "F.Paste")
			(net "P12V_STBY_VIN_PU1")
		)
		(pad "18" smd rect
			(at 0.500126 2.449322 180)
			(size 0.3048 1.1176)
			(layers "F.Cu" "F.Mask" "F.Paste")
			(net "P5V_STBY_VREG")
		)
		(pad "19" smd rect
			(at 0.999998 2.449322 180)
			(size 0.3048 1.1176)
			(layers "F.Cu" "F.Mask" "F.Paste")
			(net "P5V_VDD")
		)
		(pad "20" smd rect
			(at 1.500124 2.449322 180)
			(size 0.3048 1.1176)
			(layers "F.Cu" "F.Mask" "F.Paste")
			(net "P5V_MODE")
		)
		(pad "21" smd rect
			(at 1.999996 2.449322 180)
			(size 0.3048 1.1176)
			(layers "F.Cu" "F.Mask" "F.Paste")
			(net "P5V_TRIP")
		)
		(pad "22" smd rect
			(at 2.500122 2.449322 180)
			(size 0.3048 1.1176)
			(layers "F.Cu" "F.Mask" "F.Paste")
			(net "P5V_RF")
		)
		(pad "23" smd custom
			(at 0 0 180)
			(size 0.83185 0.83185)
			(layers "F.Cu" "F.Mask" "F.Paste")
			(net "GND")
			(options
				(clearance outline)
				(anchor circle)
			)
			(primitives
				(gr_poly
					(pts
						(xy -2.7813 1.6637) (xy -2.7813 1.2954) (xy -3.048 1.2954) (xy -3.048 0.9525) (xy -2.7813 0.9525)
						(xy -2.7813 -0.9525) (xy -3.048 -0.9525) (xy -3.048 -1.2954) (xy -2.7813 -1.2954) (xy -2.7813 -1.6637)
						(xy 2.7813 -1.6637) (xy 2.7813 -1.2954) (xy 3.048 -1.2954) (xy 3.048 -0.9525) (xy 2.7813 -0.9525)
						(xy 2.7813 0.9525) (xy 3.048 0.9525) (xy 3.048 1.2954) (xy 2.7813 1.2954) (xy 2.7813 1.6637)
					)
					(width 0)
					(fill yes)
				)
			)
		)
	)
)
